(kicad_pcb
	(version 20260206)
	(generator "pcbnew")
	(generator_version "10.0")
	(general
		(thickness 1.6)
		(legacy_teardrops no)
	)
	(paper "A4")
	(title_block
		(title "03242023_DA0F0TMBIJ0_F0T_Motherboard_J_brd_V01_OCP.brd")
		(comment 1 "Grand Teton / footprints 616-621 of 6105")
	)
	(layers
		(0 "F.Cu" signal "TOP")
		(4 "In1.Cu" signal "GND")
		(6 "In2.Cu" signal "IN1")
		(8 "In3.Cu" signal "GND1")
		(10 "In4.Cu" signal "IN2")
		(12 "In5.Cu" signal "GND2")
		(14 "In6.Cu" signal "IN3")
		(16 "In7.Cu" signal "GND3")
		(18 "In8.Cu" signal "VCC")
		(20 "In9.Cu" signal "VCC1")
		(22 "In10.Cu" signal "GND4")
		(24 "In11.Cu" signal "IN4")
		(26 "In12.Cu" signal "GND5")
		(28 "In13.Cu" signal "IN5")
		(30 "In14.Cu" signal "GND6")
		(32 "In15.Cu" signal "IN6")
		(34 "In16.Cu" signal "GND7")
		(2 "B.Cu" signal "BOTTOM")
		(9 "F.Adhes" user "F.Adhesive")
		(11 "B.Adhes" user "B.Adhesive")
		(13 "F.Paste" user "Package Geometry/Pastemask Top")
		(15 "B.Paste" user "Package Geometry/Pastemask Bottom")
		(5 "F.SilkS" user "Ref Des/Silkscreen Top")
		(7 "B.SilkS" user "Ref Des/Silkscreen Bottom")
		(1 "F.Mask" user "Board Geometry/Soldermask Top")
		(3 "B.Mask" user "Board Geometry/Soldermask Bottom")
		(17 "Dwgs.User" user "User.Drawings")
		(19 "Cmts.User" user "User.Comments")
		(21 "Eco1.User" user "User.Eco1")
		(23 "Eco2.User" user "User.Eco2")
		(25 "Edge.Cuts" user "Board Geometry/Outline")
		(27 "Margin" user)
		(31 "F.CrtYd" user "Package Geometry/Place Bound Top")
		(29 "B.CrtYd" user "Package Geometry/Place Bound Bottom")
		(35 "F.Fab" user "Ref Des/Assembly Top")
		(33 "B.Fab" user "Ref Des/Assembly Bottom")
	)
	(footprint ""
		(layer "F.Cu")
		(at 428.62373 -119.349012 180)
		(property "Reference" "PC632"
			(at 0 0 180)
			(layer "F.SilkS")
			(hide yes)
			(effects
				(font
					(size 1.27 1.27)
				)
			)
		)
		(property "Value" ""
			(at 0 0 180)
			(layer "F.Fab")
			(effects
				(font
					(size 1.27 1.27)
				)
			)
		)
		(duplicate_pad_numbers_are_jumpers no)
		(fp_line
			(start 0.7874 0.4064)
			(end -0.7874 0.4064)
			(stroke
				(width 0.1524)
				(type default)
			)
			(layer "F.SilkS")
		)
		(fp_line
			(start 0.7874 -0.4064)
			(end 0.7874 0.4064)
			(stroke
				(width 0.1524)
				(type default)
			)
			(layer "F.SilkS")
		)
		(fp_line
			(start -0.7874 0.4064)
			(end -0.7874 -0.4064)
			(stroke
				(width 0.1524)
				(type default)
			)
			(layer "F.SilkS")
		)
		(fp_line
			(start -0.7874 -0.4064)
			(end 0.7874 -0.4064)
			(stroke
				(width 0.1524)
				(type default)
			)
			(layer "F.SilkS")
		)
		(fp_line
			(start 0.67945 0.3048)
			(end 0.120396 0.3048)
			(stroke
				(width 0.1)
				(type default)
			)
			(layer "F.Fab")
		)
		(fp_line
			(start 0.67945 -0.3048)
			(end 0.67945 0.3048)
			(stroke
				(width 0.1)
				(type default)
			)
			(layer "F.Fab")
		)
		(fp_line
			(start 0.12065 -0.2794)
			(end 0.12065 -0.3048)
			(stroke
				(width 0.1)
				(type default)
			)
			(layer "F.Fab")
		)
		(fp_line
			(start 0.12065 -0.3048)
			(end 0.67945 -0.3048)
			(stroke
				(width 0.1)
				(type default)
			)
			(layer "F.Fab")
		)
		(fp_line
			(start 0.120396 0.3048)
			(end 0.120396 0.2794)
			(stroke
				(width 0.1)
				(type default)
			)
			(layer "F.Fab")
		)
		(fp_line
			(start 0.120396 0.2794)
			(end -0.12065 0.2794)
			(stroke
				(width 0.1)
				(type default)
			)
			(layer "F.Fab")
		)
		(fp_line
			(start -0.12065 0.3048)
			(end -0.67945 0.3048)
			(stroke
				(width 0.1)
				(type default)
			)
			(layer "F.Fab")
		)
		(fp_line
			(start -0.12065 0.2794)
			(end -0.12065 0.3048)
			(stroke
				(width 0.1)
				(type default)
			)
			(layer "F.Fab")
		)
		(fp_line
			(start -0.12065 -0.2794)
			(end 0.12065 -0.2794)
			(stroke
				(width 0.1)
				(type default)
			)
			(layer "F.Fab")
		)
		(fp_line
			(start -0.12065 -0.305054)
			(end -0.12065 -0.2794)
			(stroke
				(width 0.1)
				(type default)
			)
			(layer "F.Fab")
		)
		(fp_line
			(start -0.67945 0.3048)
			(end -0.67945 -0.305054)
			(stroke
				(width 0.1)
				(type default)
			)
			(layer "F.Fab")
		)
		(fp_line
			(start -0.67945 -0.305054)
			(end -0.12065 -0.305054)
			(stroke
				(width 0.1)
				(type default)
			)
			(layer "F.Fab")
		)
		(pad "1" smd circle
			(at -0.40005 0 180)
			(size 0 0)
			(layers "F.Cu" "F.Mask" "F.Paste")
			(net "PVCCD_HV_CPU0_VCC")
		)
		(pad "2" smd circle
			(at 0.40005 0 180)
			(size 0 0)
			(layers "F.Cu" "F.Mask" "F.Paste")
			(net "GND")
		)
	)
	(footprint ""
		(layer "F.Cu")
		(at 377.300998 -75.74788 180)
		(property "Reference" "PL170"
			(at 8.649208 2.006092 0)
			(unlocked yes)
			(layer "F.SilkS")
			(effects
				(font
					(size 0.7874 0.5842)
					(thickness 0.1524)
				)
				(justify left)
			)
		)
		(property "Value" ""
			(at 0 0 180)
			(layer "F.Fab")
			(effects
				(font
					(size 1.27 1.27)
				)
			)
		)
		(duplicate_pad_numbers_are_jumpers no)
		(fp_line
			(start 3.64998 3.350006)
			(end -3.64998 3.350006)
			(stroke
				(width 0.1524)
				(type default)
			)
			(layer "F.SilkS")
		)
		(fp_line
			(start 3.64998 1.8034)
			(end 3.64998 3.350006)
			(stroke
				(width 0.1524)
				(type default)
			)
			(layer "F.SilkS")
		)
		(fp_line
			(start 3.64998 -3.350006)
			(end 3.64998 -1.8034)
			(stroke
				(width 0.1524)
				(type default)
			)
			(layer "F.SilkS")
		)
		(fp_line
			(start -3.64998 3.350006)
			(end -3.64998 1.8288)
			(stroke
				(width 0.1524)
				(type default)
			)
			(layer "F.SilkS")
		)
		(fp_line
			(start -3.64998 -1.8034)
			(end -3.64998 -3.350006)
			(stroke
				(width 0.1524)
				(type default)
			)
			(layer "F.SilkS")
		)
		(fp_line
			(start -3.6576 -3.350006)
			(end 3.64998 -3.350006)
			(stroke
				(width 0.1524)
				(type default)
			)
			(layer "F.SilkS")
		)
		(fp_line
			(start 3.64998 3.350006)
			(end -3.64998 3.350006)
			(stroke
				(width 0.1)
				(type default)
			)
			(layer "F.Fab")
		)
		(fp_line
			(start 3.64998 -3.350006)
			(end 3.64998 3.350006)
			(stroke
				(width 0.1)
				(type default)
			)
			(layer "F.Fab")
		)
		(fp_line
			(start -3.64998 3.350006)
			(end -3.64998 -3.350006)
			(stroke
				(width 0.1)
				(type default)
			)
			(layer "F.Fab")
		)
		(fp_line
			(start -3.64998 -3.350006)
			(end 3.64998 -3.350006)
			(stroke
				(width 0.1)
				(type default)
			)
			(layer "F.Fab")
		)
		(pad "1" smd rect
			(at -2.92481 0 180)
			(size 2.15392 3.302)
			(layers "F.Cu" "F.Mask" "F.Paste")
			(net "SW_P1V8_PCH_AUX_SW")
		)
		(pad "2" smd rect
			(at 2.92481 0 180)
			(size 2.15392 3.302)
			(layers "F.Cu" "F.Mask" "F.Paste")
			(net "P1V8_PCH_AUX")
		)
	)
	(footprint ""
		(layer "F.Cu")
		(at 102.844346 -357.562658)
		(property "Reference" "R310"
			(at 0 0 0)
			(layer "F.SilkS")
			(hide yes)
			(effects
				(font
					(size 1.27 1.27)
				)
			)
		)
		(property "Value" ""
			(at 0 0 0)
			(layer "F.Fab")
			(effects
				(font
					(size 1.27 1.27)
				)
			)
		)
		(duplicate_pad_numbers_are_jumpers no)
		(fp_line
			(start -0.7874 -0.4064)
			(end 0.7874 -0.4064)
			(stroke
				(width 0.1524)
				(type default)
			)
			(layer "F.SilkS")
		)
		(fp_line
			(start -0.7874 0.4064)
			(end -0.7874 -0.4064)
			(stroke
				(width 0.1524)
				(type default)
			)
			(layer "F.SilkS")
		)
		(fp_line
			(start 0.7874 -0.4064)
			(end 0.7874 0.4064)
			(stroke
				(width 0.1524)
				(type default)
			)
			(layer "F.SilkS")
		)
		(fp_line
			(start 0.7874 0.4064)
			(end -0.7874 0.4064)
			(stroke
				(width 0.1524)
				(type default)
			)
			(layer "F.SilkS")
		)
		(fp_line
			(start -0.67945 -0.305054)
			(end -0.12065 -0.305054)
			(stroke
				(width 0.1)
				(type default)
			)
			(layer "F.Fab")
		)
		(fp_line
			(start -0.67945 0.3048)
			(end -0.67945 -0.305054)
			(stroke
				(width 0.1)
				(type default)
			)
			(layer "F.Fab")
		)
		(fp_line
			(start -0.12065 -0.305054)
			(end -0.12065 -0.2794)
			(stroke
				(width 0.1)
				(type default)
			)
			(layer "F.Fab")
		)
		(fp_line
			(start -0.12065 -0.2794)
			(end 0.12065 -0.2794)
			(stroke
				(width 0.1)
				(type default)
			)
			(layer "F.Fab")
		)
		(fp_line
			(start -0.12065 0.2794)
			(end -0.12065 0.3048)
			(stroke
				(width 0.1)
				(type default)
			)
			(layer "F.Fab")
		)
		(fp_line
			(start -0.12065 0.3048)
			(end -0.67945 0.3048)
			(stroke
				(width 0.1)
				(type default)
			)
			(layer "F.Fab")
		)
		(fp_line
			(start 0.120396 0.2794)
			(end -0.12065 0.2794)
			(stroke
				(width 0.1)
				(type default)
			)
			(layer "F.Fab")
		)
		(fp_line
			(start 0.120396 0.3048)
			(end 0.120396 0.2794)
			(stroke
				(width 0.1)
				(type default)
			)
			(layer "F.Fab")
		)
		(fp_line
			(start 0.12065 -0.3048)
			(end 0.67945 -0.3048)
			(stroke
				(width 0.1)
				(type default)
			)
			(layer "F.Fab")
		)
		(fp_line
			(start 0.12065 -0.2794)
			(end 0.12065 -0.3048)
			(stroke
				(width 0.1)
				(type default)
			)
			(layer "F.Fab")
		)
		(fp_line
			(start 0.67945 -0.3048)
			(end 0.67945 0.3048)
			(stroke
				(width 0.1)
				(type default)
			)
			(layer "F.Fab")
		)
		(fp_line
			(start 0.67945 0.3048)
			(end 0.120396 0.3048)
			(stroke
				(width 0.1)
				(type default)
			)
			(layer "F.Fab")
		)
		(pad "1" smd circle
			(at -0.40005 0)
			(size 0 0)
			(layers "F.Cu" "F.Mask" "F.Paste")
			(net "SVID_CLK0_CPU1_R")
		)
		(pad "2" smd circle
			(at 0.40005 0)
			(size 0 0)
			(layers "F.Cu" "F.Mask" "F.Paste")
			(net "SVID_CLK_PVCCIN_CPU1_R")
		)
	)
	(footprint ""
		(layer "F.Cu")
		(at 434.808122 -32.573468 180)
		(property "Reference" "R3870"
			(at 0 0 180)
			(layer "F.SilkS")
			(hide yes)
			(effects
				(font
					(size 1.27 1.27)
				)
			)
		)
		(property "Value" ""
			(at 0 0 180)
			(layer "F.Fab")
			(effects
				(font
					(size 1.27 1.27)
				)
			)
		)
		(duplicate_pad_numbers_are_jumpers no)
		(fp_line
			(start 0.7874 0.4064)
			(end -0.7874 0.4064)
			(stroke
				(width 0.1524)
				(type default)
			)
			(layer "F.SilkS")
		)
		(fp_line
			(start 0.7874 -0.4064)
			(end 0.7874 0.4064)
			(stroke
				(width 0.1524)
				(type default)
			)
			(layer "F.SilkS")
		)
		(fp_line
			(start -0.7874 0.4064)
			(end -0.7874 -0.4064)
			(stroke
				(width 0.1524)
				(type default)
			)
			(layer "F.SilkS")
		)
		(fp_line
			(start -0.7874 -0.4064)
			(end 0.7874 -0.4064)
			(stroke
				(width 0.1524)
				(type default)
			)
			(layer "F.SilkS")
		)
		(fp_line
			(start 0.67945 0.3048)
			(end 0.120396 0.3048)
			(stroke
				(width 0.1)
				(type default)
			)
			(layer "F.Fab")
		)
		(fp_line
			(start 0.67945 -0.3048)
			(end 0.67945 0.3048)
			(stroke
				(width 0.1)
				(type default)
			)
			(layer "F.Fab")
		)
		(fp_line
			(start 0.12065 -0.2794)
			(end 0.12065 -0.3048)
			(stroke
				(width 0.1)
				(type default)
			)
			(layer "F.Fab")
		)
		(fp_line
			(start 0.12065 -0.3048)
			(end 0.67945 -0.3048)
			(stroke
				(width 0.1)
				(type default)
			)
			(layer "F.Fab")
		)
		(fp_line
			(start 0.120396 0.3048)
			(end 0.120396 0.2794)
			(stroke
				(width 0.1)
				(type default)
			)
			(layer "F.Fab")
		)
		(fp_line
			(start 0.120396 0.2794)
			(end -0.12065 0.2794)
			(stroke
				(width 0.1)
				(type default)
			)
			(layer "F.Fab")
		)
		(fp_line
			(start -0.12065 0.3048)
			(end -0.67945 0.3048)
			(stroke
				(width 0.1)
				(type default)
			)
			(layer "F.Fab")
		)
		(fp_line
			(start -0.12065 0.2794)
			(end -0.12065 0.3048)
			(stroke
				(width 0.1)
				(type default)
			)
			(layer "F.Fab")
		)
		(fp_line
			(start -0.12065 -0.2794)
			(end 0.12065 -0.2794)
			(stroke
				(width 0.1)
				(type default)
			)
			(layer "F.Fab")
		)
		(fp_line
			(start -0.12065 -0.305054)
			(end -0.12065 -0.2794)
			(stroke
				(width 0.1)
				(type default)
			)
			(layer "F.Fab")
		)
		(fp_line
			(start -0.67945 0.3048)
			(end -0.67945 -0.305054)
			(stroke
				(width 0.1)
				(type default)
			)
			(layer "F.Fab")
		)
		(fp_line
			(start -0.67945 -0.305054)
			(end -0.12065 -0.305054)
			(stroke
				(width 0.1)
				(type default)
			)
			(layer "F.Fab")
		)
		(pad "1" smd rect
			(at -0.40005 0)
			(size 0.4572 0.508)
			(layers "F.Cu" "F.Mask" "F.Paste")
			(net "P12V_OCP_SENSE_1")
		)
		(pad "2" smd rect
			(at 0.40005 0)
			(size 0.4572 0.508)
			(layers "F.Cu" "F.Mask" "F.Paste")
			(net "P12V_OCP_SFF_ISENSE_MAM_TIC")
		)
	)
	(footprint ""
		(layer "F.Cu")
		(at 283.826712 -363.881416)
		(property "Reference" "PR447"
			(at 0 0 0)
			(layer "F.SilkS")
			(hide yes)
			(effects
				(font
					(size 1.27 1.27)
				)
			)
		)
		(property "Value" ""
			(at 0 0 0)
			(layer "F.Fab")
			(effects
				(font
					(size 1.27 1.27)
				)
			)
		)
		(duplicate_pad_numbers_are_jumpers no)
		(fp_line
			(start -0.7874 -0.4064)
			(end 0.7874 -0.4064)
			(stroke
				(width 0.1524)
				(type default)
			)
			(layer "F.SilkS")
		)
		(fp_line
			(start -0.7874 0.4064)
			(end -0.7874 -0.4064)
			(stroke
				(width 0.1524)
				(type default)
			)
			(layer "F.SilkS")
		)
		(fp_line
			(start 0.7874 -0.4064)
			(end 0.7874 0.4064)
			(stroke
				(width 0.1524)
				(type default)
			)
			(layer "F.SilkS")
		)
		(fp_line
			(start 0.7874 0.4064)
			(end -0.7874 0.4064)
			(stroke
				(width 0.1524)
				(type default)
			)
			(layer "F.SilkS")
		)
		(fp_line
			(start -0.67945 -0.305054)
			(end -0.12065 -0.305054)
			(stroke
				(width 0.1)
				(type default)
			)
			(layer "F.Fab")
		)
		(fp_line
			(start -0.67945 0.3048)
			(end -0.67945 -0.305054)
			(stroke
				(width 0.1)
				(type default)
			)
			(layer "F.Fab")
		)
		(fp_line
			(start -0.12065 -0.305054)
			(end -0.12065 -0.2794)
			(stroke
				(width 0.1)
				(type default)
			)
			(layer "F.Fab")
		)
		(fp_line
			(start -0.12065 -0.2794)
			(end 0.12065 -0.2794)
			(stroke
				(width 0.1)
				(type default)
			)
			(layer "F.Fab")
		)
		(fp_line
			(start -0.12065 0.2794)
			(end -0.12065 0.3048)
			(stroke
				(width 0.1)
				(type default)
			)
			(layer "F.Fab")
		)
		(fp_line
			(start -0.12065 0.3048)
			(end -0.67945 0.3048)
			(stroke
				(width 0.1)
				(type default)
			)
			(layer "F.Fab")
		)
		(fp_line
			(start 0.120396 0.2794)
			(end -0.12065 0.2794)
			(stroke
				(width 0.1)
				(type default)
			)
			(layer "F.Fab")
		)
		(fp_line
			(start 0.120396 0.3048)
			(end 0.120396 0.2794)
			(stroke
				(width 0.1)
				(type default)
			)
			(layer "F.Fab")
		)
		(fp_line
			(start 0.12065 -0.3048)
			(end 0.67945 -0.3048)
			(stroke
				(width 0.1)
				(type default)
			)
			(layer "F.Fab")
		)
		(fp_line
			(start 0.12065 -0.2794)
			(end 0.12065 -0.3048)
			(stroke
				(width 0.1)
				(type default)
			)
			(layer "F.Fab")
		)
		(fp_line
			(start 0.67945 -0.3048)
			(end 0.67945 0.3048)
			(stroke
				(width 0.1)
				(type default)
			)
			(layer "F.Fab")
		)
		(fp_line
			(start 0.67945 0.3048)
			(end 0.120396 0.3048)
			(stroke
				(width 0.1)
				(type default)
			)
			(layer "F.Fab")
		)
		(pad "1" smd circle
			(at -0.40005 0)
			(size 0 0)
			(layers "F.Cu" "F.Mask" "F.Paste")
			(net "P5V")
		)
		(pad "2" smd circle
			(at 0.40005 0)
			(size 0 0)
			(layers "F.Cu" "F.Mask" "F.Paste")
			(net "PVCCFA_EHV_FIVRA_CPU0_PVCC2")
		)
	)
	(footprint ""
		(layer "F.Cu")
		(at 336.947256 -66.424556)
		(property "Reference" "C104"
			(at 0 0 0)
			(layer "F.SilkS")
			(hide yes)
			(effects
				(font
					(size 1.27 1.27)
				)
			)
		)
		(property "Value" ""
			(at 0 0 0)
			(layer "F.Fab")
			(effects
				(font
					(size 1.27 1.27)
				)
			)
		)
		(duplicate_pad_numbers_are_jumpers no)
		(fp_line
			(start -0.7874 -0.4064)
			(end 0.7874 -0.4064)
			(stroke
				(width 0.1524)
				(type default)
			)
			(layer "F.SilkS")
		)
		(fp_line
			(start -0.7874 0.4064)
			(end -0.7874 -0.4064)
			(stroke
				(width 0.1524)
				(type default)
			)
			(layer "F.SilkS")
		)
		(fp_line
			(start 0.7874 -0.4064)
			(end 0.7874 0.4064)
			(stroke
				(width 0.1524)
				(type default)
			)
			(layer "F.SilkS")
		)
		(fp_line
			(start 0.7874 0.4064)
			(end -0.7874 0.4064)
			(stroke
				(width 0.1524)
				(type default)
			)
			(layer "F.SilkS")
		)
		(fp_line
			(start -0.67945 -0.305054)
			(end -0.12065 -0.305054)
			(stroke
				(width 0.1)
				(type default)
			)
			(layer "F.Fab")
		)
		(fp_line
			(start -0.67945 0.3048)
			(end -0.67945 -0.305054)
			(stroke
				(width 0.1)
				(type default)
			)
			(layer "F.Fab")
		)
		(fp_line
			(start -0.12065 -0.305054)
			(end -0.12065 -0.2794)
			(stroke
				(width 0.1)
				(type default)
			)
			(layer "F.Fab")
		)
		(fp_line
			(start -0.12065 -0.2794)
			(end 0.12065 -0.2794)
			(stroke
				(width 0.1)
				(type default)
			)
			(layer "F.Fab")
		)
		(fp_line
			(start -0.12065 0.2794)
			(end -0.12065 0.3048)
			(stroke
				(width 0.1)
				(type default)
			)
			(layer "F.Fab")
		)
		(fp_line
			(start -0.12065 0.3048)
			(end -0.67945 0.3048)
			(stroke
				(width 0.1)
				(type default)
			)
			(layer "F.Fab")
		)
		(fp_line
			(start 0.120396 0.2794)
			(end -0.12065 0.2794)
			(stroke
				(width 0.1)
				(type default)
			)
			(layer "F.Fab")
		)
		(fp_line
			(start 0.120396 0.3048)
			(end 0.120396 0.2794)
			(stroke
				(width 0.1)
				(type default)
			)
			(layer "F.Fab")
		)
		(fp_line
			(start 0.12065 -0.3048)
			(end 0.67945 -0.3048)
			(stroke
				(width 0.1)
				(type default)
			)
			(layer "F.Fab")
		)
		(fp_line
			(start 0.12065 -0.2794)
			(end 0.12065 -0.3048)
			(stroke
				(width 0.1)
				(type default)
			)
			(layer "F.Fab")
		)
		(fp_line
			(start 0.67945 -0.3048)
			(end 0.67945 0.3048)
			(stroke
				(width 0.1)
				(type default)
			)
			(layer "F.Fab")
		)
		(fp_line
			(start 0.67945 0.3048)
			(end 0.120396 0.3048)
			(stroke
				(width 0.1)
				(type default)
			)
			(layer "F.Fab")
		)
		(pad "1" smd circle
			(at -0.40005 0)
			(size 0 0)
			(layers "F.Cu" "F.Mask" "F.Paste")
			(net "XTAL_PCH_25M_OUT")
		)
		(pad "2" smd circle
			(at 0.40005 0)
			(size 0 0)
			(layers "F.Cu" "F.Mask" "F.Paste")
			(net "GND")
		)
	)
)
